# S9S_MB_2U (Grand Teton) — schematic netlist excerpt (pin names and nets, part order shuffled) for the footprints in the layout excerpt that follows; sources: Cadence DE-HDL packaged netlist, KiCad conversion of 03242023_DA0F0TMBIJ0_F0T_Motherboard_J_brd_V01_OCP.brd

PU204  RS31312R  IC  pkg QFN22_TH_3X5  page 157
  EN  = P12V_OCP_EN_1_R2
  LOADEN  = GND
  ENTM  = GND
  TIMER  = P12V_OCP_TIMER_1
  ISET  = P12V_OCP_ISET_1
  SS  = P12V_OCP_SS_1
  GND  = GND
  IMON  = P12V_OCP_IMON_1
  FLTB  = P12V_OCP_FLTB_1
  PG  = HP_LVC3_OCP_V3_1_P12V_PWRGD
  OV  = P12V_OCP_OV_FB_1
  AVIN  = P12V_OCP_AVIN_PD_1
  VOUT_13  = P12V_OCP_SFF
  VOUT_14  = P12V_OCP_SFF
  VOUT_15  = P12V_OCP_SFF
  VOUT_16  = P12V_OCP_SFF
  VOUT_17  = P12V_OCP_SFF
  VOUT_18  = P12V_OCP_SFF
  VOUT_19  = P12V_OCP_SFF
  VOUT_20  = P12V_OCP_SFF
  VIN_21_22  = P12V_AUX
  VIN_23  = P12V_AUX
  VIN_24  = P12V_AUX
  VIN_25  = P12V_AUX
  VIN_26  = P12V_AUX

(kicad_pcb
	(version 20260206)
	(generator "pcbnew")
	(generator_version "10.0")
	(general
		(thickness 1.6)
		(legacy_teardrops no)
	)
	(paper "A4")
	(title_block
		(title "03242023_DA0F0TMBIJ0_F0T_Motherboard_J_brd_V01_OCP.brd")
		(comment 1 "Grand Teton / footprint 993 of 6105 (PU204), pads 1-25 of 25")
	)
	(layers
		(0 "F.Cu" signal "TOP")
		(4 "In1.Cu" signal "GND")
		(6 "In2.Cu" signal "IN1")
		(8 "In3.Cu" signal "GND1")
		(10 "In4.Cu" signal "IN2")
		(12 "In5.Cu" signal "GND2")
		(14 "In6.Cu" signal "IN3")
		(16 "In7.Cu" signal "GND3")
		(18 "In8.Cu" signal "VCC")
		(20 "In9.Cu" signal "VCC1")
		(22 "In10.Cu" signal "GND4")
		(24 "In11.Cu" signal "IN4")
		(26 "In12.Cu" signal "GND5")
		(28 "In13.Cu" signal "IN5")
		(30 "In14.Cu" signal "GND6")
		(32 "In15.Cu" signal "IN6")
		(34 "In16.Cu" signal "GND7")
		(2 "B.Cu" signal "BOTTOM")
		(9 "F.Adhes" user "F.Adhesive")
		(11 "B.Adhes" user "B.Adhesive")
		(13 "F.Paste" user "Package Geometry/Pastemask Top")
		(15 "B.Paste" user "Package Geometry/Pastemask Bottom")
		(5 "F.SilkS" user "Ref Des/Silkscreen Top")
		(7 "B.SilkS" user "Ref Des/Silkscreen Bottom")
		(1 "F.Mask" user "Board Geometry/Soldermask Top")
		(3 "B.Mask" user "Board Geometry/Soldermask Bottom")
		(17 "Dwgs.User" user "User.Drawings")
		(19 "Cmts.User" user "User.Comments")
		(21 "Eco1.User" user "User.Eco1")
		(23 "Eco2.User" user "User.Eco2")
		(25 "Edge.Cuts" user "Board Geometry/Outline")
		(27 "Margin" user)
		(31 "F.CrtYd" user "Package Geometry/Place Bound Top")
		(29 "B.CrtYd" user "Package Geometry/Place Bound Bottom")
		(35 "F.Fab" user "Ref Des/Assembly Top")
		(33 "B.Fab" user "Ref Des/Assembly Bottom")
	)
	(footprint ""
		(layer "F.Cu")
		(at 442.353192 -28.175458 -90)
		(property "Reference" "PU204"
			(at 1.50749 -4.241038 0)
			(unlocked yes)
			(layer "F.SilkS")
			(effects
				(font
					(size 0.7874 0.5842)
					(thickness 0.1524)
				)
				(justify left)
			)
		)
		(property "Value" ""
			(at 0 0 270)
			(layer "F.Fab")
			(effects
				(font
					(size 1.27 1.27)
				)
			)
		)
		(duplicate_pad_numbers_are_jumpers no)
		(pad "1" smd circle
			(at -1.374902 -1.999996 180)
			(size 0 0)
			(layers "F.Cu" "F.Mask" "F.Paste")
			(net "P12V_OCP_EN_1_R2")
		)
		(pad "2" smd rect
			(at -1.400048 -1.500124 180)
			(size 0.254 0.8128)
			(layers "F.Cu" "F.Mask" "F.Paste")
			(net "GND")
		)
		(pad "3" smd rect
			(at -1.400048 -0.999998 180)
			(size 0.254 0.8128)
			(layers "F.Cu" "F.Mask" "F.Paste")
			(net "GND")
		)
		(pad "4" smd rect
			(at -1.400048 -0.499872 180)
			(size 0.254 0.8128)
			(layers "F.Cu" "F.Mask" "F.Paste")
			(net "P12V_OCP_TIMER_1")
		)
		(pad "5" smd rect
			(at -1.400048 0 180)
			(size 0.254 0.8128)
			(layers "F.Cu" "F.Mask" "F.Paste")
			(net "P12V_OCP_ISET_1")
		)
		(pad "6" smd rect
			(at -1.400048 0.499872 180)
			(size 0.254 0.8128)
			(layers "F.Cu" "F.Mask" "F.Paste")
			(net "P12V_OCP_SS_1")
		)
		(pad "7" smd rect
			(at -1.400048 0.999998 180)
			(size 0.254 0.8128)
			(layers "F.Cu" "F.Mask" "F.Paste")
			(net "GND")
		)
		(pad "8" smd rect
			(at -1.400048 1.500124 180)
			(size 0.254 0.8128)
			(layers "F.Cu" "F.Mask" "F.Paste")
			(net "P12V_OCP_IMON_1")
		)
		(pad "9" smd rect
			(at -1.400048 1.999996 180)
			(size 0.254 0.8128)
			(layers "F.Cu" "F.Mask" "F.Paste")
			(net "P12V_OCP_FLTB_1")
		)
		(pad "10" smd rect
			(at -0.499872 2.400046 270)
			(size 0.254 0.8128)
			(layers "F.Cu" "F.Mask" "F.Paste")
			(net "HP_LVC3_OCP_V3_1_P12V_PWRGD")
		)
		(pad "11" smd rect
			(at 0.499872 2.400046 270)
			(size 0.254 0.8128)
			(layers "F.Cu" "F.Mask" "F.Paste")
			(net "P12V_OCP_OV_FB_1")
		)
		(pad "12" smd rect
			(at 1.400048 1.999996 180)
			(size 0.254 0.8128)
			(layers "F.Cu" "F.Mask" "F.Paste")
			(net "P12V_OCP_AVIN_PD_1")
		)
		(pad "13" smd rect
			(at 1.400048 1.500124 180)
			(size 0.254 0.8128)
			(layers "F.Cu" "F.Mask" "F.Paste")
			(net "P12V_OCP_SFF")
		)
		(pad "14" smd rect
			(at 1.400048 0.999998 180)
			(size 0.254 0.8128)
			(layers "F.Cu" "F.Mask" "F.Paste")
			(net "P12V_OCP_SFF")
		)
		(pad "15" smd rect
			(at 1.400048 0.499872 180)
			(size 0.254 0.8128)
			(layers "F.Cu" "F.Mask" "F.Paste")
			(net "P12V_OCP_SFF")
		)
		(pad "16" smd rect
			(at 1.400048 0 180)
			(size 0.254 0.8128)
			(layers "F.Cu" "F.Mask" "F.Paste")
			(net "P12V_OCP_SFF")
		)
		(pad "17" smd rect
			(at 1.400048 -0.499872 180)
			(size 0.254 0.8128)
			(layers "F.Cu" "F.Mask" "F.Paste")
			(net "P12V_OCP_SFF")
		)
		(pad "18" smd rect
			(at 1.400048 -0.999998 180)
			(size 0.254 0.8128)
			(layers "F.Cu" "F.Mask" "F.Paste")
			(net "P12V_OCP_SFF")
		)
		(pad "19" smd rect
			(at 1.400048 -1.500124 180)
			(size 0.254 0.8128)
			(layers "F.Cu" "F.Mask" "F.Paste")
			(net "P12V_OCP_SFF")
		)
		(pad "20" smd rect
			(at 1.400048 -1.999996 180)
			(size 0.254 0.8128)
			(layers "F.Cu" "F.Mask" "F.Paste")
			(net "P12V_OCP_SFF")
		)
		(pad "21_22" smd circle
			(at 0.499872 -2.337562 180)
			(size 0 0)
			(layers "F.Cu" "F.Mask" "F.Paste")
			(net "P12V_AUX")
		)
		(pad "23" smd rect
			(at 0 -1.100074 180)
			(size 0.254 1.27)
			(layers "F.Cu" "F.Mask" "F.Paste")
			(net "P12V_AUX")
		)
		(pad "24" smd rect
			(at 0 -0.199898 180)
			(size 0.254 1.27)
			(layers "F.Cu" "F.Mask" "F.Paste")
			(net "P12V_AUX")
		)
		(pad "25" smd rect
			(at 0 0.700024 180)
			(size 0.254 1.27)
			(layers "F.Cu" "F.Mask" "F.Paste")
			(net "P12V_AUX")
		)
		(pad "26" smd rect
			(at 0 1.599946 180)
			(size 0.254 1.27)
			(layers "F.Cu" "F.Mask" "F.Paste")
			(net "P12V_AUX")
		)
	)
)
